# SCM (Grand Teton) — schematic netlist excerpt (pin names and nets, part order shuffled) for the footprints in the layout excerpt that follows; sources: Cadence DE-HDL packaged netlist, KiCad conversion of 12092022_DA0F0TMDCD0_F0T_Management_Board_D_brd_V3_OCP.brd

R870  Q_RES  4.7K 1% EMPTY  pkg 0402LF  page 44 : A = P3V3_AUX ; B = PD_BIOS_MUX_EN_N
R188  Q_RES  1K 1% CHIP  pkg 0402LF  page 14 : A = P1V2_P1V0_I3C_VDDL1 ; B = I3C3_SPD_SCL

(kicad_pcb
	(version 20260206)
	(generator "pcbnew")
	(generator_version "10.0")
	(general
		(thickness 1.6)
		(legacy_teardrops no)
	)
	(paper "A4")
	(title_block
		(title "12092022_DA0F0TMDCD0_F0T_Management_Board_D_brd_V3_OCP.brd")
		(comment 1 "Grand Teton / footprints 1347-1348 of 1440")
	)
	(layers
		(0 "F.Cu" signal "TOP")
		(4 "In1.Cu" signal "GND")
		(6 "In2.Cu" signal "IN1")
		(8 "In3.Cu" signal "GND1")
		(10 "In4.Cu" signal "IN2")
		(12 "In5.Cu" signal "VCC")
		(14 "In6.Cu" signal "VCC1")
		(16 "In7.Cu" signal "IN3")
		(18 "In8.Cu" signal "GND2")
		(20 "In9.Cu" signal "IN4")
		(22 "In10.Cu" signal "GND3")
		(2 "B.Cu" signal "BOTTOM")
		(9 "F.Adhes" user "F.Adhesive")
		(11 "B.Adhes" user "B.Adhesive")
		(13 "F.Paste" user "Package Geometry/Pastemask Top")
		(15 "B.Paste" user "Package Geometry/Pastemask Bottom")
		(5 "F.SilkS" user "Ref Des/Silkscreen Top")
		(7 "B.SilkS" user "Ref Des/Silkscreen Bottom")
		(1 "F.Mask" user "Board Geometry/Soldermask Top")
		(3 "B.Mask" user "Board Geometry/Soldermask Bottom")
		(17 "Dwgs.User" user "User.Drawings")
		(19 "Cmts.User" user "User.Comments")
		(21 "Eco1.User" user "User.Eco1")
		(23 "Eco2.User" user "User.Eco2")
		(25 "Edge.Cuts" user "Board Geometry/Outline")
		(27 "Margin" user)
		(31 "F.CrtYd" user "Package Geometry/Place Bound Top")
		(29 "B.CrtYd" user "Package Geometry/Place Bound Bottom")
		(35 "F.Fab" user "Ref Des/Assembly Top")
		(33 "B.Fab" user "Ref Des/Assembly Bottom")
	)
	(footprint ""
		(layer "B.Cu")
		(at 37.4015 -102.0445 180)
		(property "Reference" "R870"
			(at 0 0 0)
			(layer "B.SilkS")
			(hide yes)
			(effects
				(font
					(size 1.27 1.27)
				)
				(justify mirror)
			)
		)
		(property "Value" ""
			(at 0 0 0)
			(layer "B.Fab")
			(effects
				(font
					(size 1.27 1.27)
				)
				(justify mirror)
			)
		)
		(duplicate_pad_numbers_are_jumpers no)
		(fp_line
			(start 0.7874 0.4064)
			(end 0.7874 -0.4064)
			(stroke
				(width 0.1524)
				(type default)
			)
			(layer "B.SilkS")
		)
		(fp_line
			(start 0.7874 -0.4064)
			(end -0.7874 -0.4064)
			(stroke
				(width 0.1524)
				(type default)
			)
			(layer "B.SilkS")
		)
		(fp_line
			(start -0.7874 0.4064)
			(end 0.7874 0.4064)
			(stroke
				(width 0.1524)
				(type default)
			)
			(layer "B.SilkS")
		)
		(fp_line
			(start -0.7874 -0.4064)
			(end -0.7874 0.4064)
			(stroke
				(width 0.1524)
				(type default)
			)
			(layer "B.SilkS")
		)
		(fp_line
			(start 0.67945 0.3048)
			(end 0.67945 -0.305054)
			(stroke
				(width 0.1)
				(type default)
			)
			(layer "B.Fab")
		)
		(fp_line
			(start 0.67945 -0.305054)
			(end 0.12065 -0.305054)
			(stroke
				(width 0.1)
				(type default)
			)
			(layer "B.Fab")
		)
		(fp_line
			(start 0.12065 0.3048)
			(end 0.67945 0.3048)
			(stroke
				(width 0.1)
				(type default)
			)
			(layer "B.Fab")
		)
		(fp_line
			(start 0.12065 0.2794)
			(end 0.12065 0.3048)
			(stroke
				(width 0.1)
				(type default)
			)
			(layer "B.Fab")
		)
		(fp_line
			(start 0.12065 -0.2794)
			(end -0.12065 -0.2794)
			(stroke
				(width 0.1)
				(type default)
			)
			(layer "B.Fab")
		)
		(fp_line
			(start 0.12065 -0.305054)
			(end 0.12065 -0.2794)
			(stroke
				(width 0.1)
				(type default)
			)
			(layer "B.Fab")
		)
		(fp_line
			(start -0.120396 0.3048)
			(end -0.120396 0.2794)
			(stroke
				(width 0.1)
				(type default)
			)
			(layer "B.Fab")
		)
		(fp_line
			(start -0.120396 0.2794)
			(end 0.12065 0.2794)
			(stroke
				(width 0.1)
				(type default)
			)
			(layer "B.Fab")
		)
		(fp_line
			(start -0.12065 -0.2794)
			(end -0.12065 -0.3048)
			(stroke
				(width 0.1)
				(type default)
			)
			(layer "B.Fab")
		)
		(fp_line
			(start -0.12065 -0.3048)
			(end -0.67945 -0.3048)
			(stroke
				(width 0.1)
				(type default)
			)
			(layer "B.Fab")
		)
		(fp_line
			(start -0.67945 0.3048)
			(end -0.120396 0.3048)
			(stroke
				(width 0.1)
				(type default)
			)
			(layer "B.Fab")
		)
		(fp_line
			(start -0.67945 -0.3048)
			(end -0.67945 0.3048)
			(stroke
				(width 0.1)
				(type default)
			)
			(layer "B.Fab")
		)
		(pad "1" smd circle
			(at 0.40005 0)
			(size 0 0)
			(layers "B.Cu" "B.Mask" "B.Paste")
			(net "P3V3_AUX")
		)
		(pad "2" smd circle
			(at -0.40005 0)
			(size 0 0)
			(layers "B.Cu" "B.Mask" "B.Paste")
			(net "PD_BIOS_MUX_EN_N")
		)
	)
	(footprint ""
		(layer "B.Cu")
		(at 40.83431 -65.776602 -90)
		(property "Reference" "R188"
			(at 0 0 90)
			(layer "B.SilkS")
			(hide yes)
			(effects
				(font
					(size 1.27 1.27)
				)
				(justify mirror)
			)
		)
		(property "Value" ""
			(at 0 0 90)
			(layer "B.Fab")
			(effects
				(font
					(size 1.27 1.27)
				)
				(justify mirror)
			)
		)
		(duplicate_pad_numbers_are_jumpers no)
		(fp_line
			(start -0.7874 0.4064)
			(end 0.7874 0.4064)
			(stroke
				(width 0.1524)
				(type default)
			)
			(layer "B.SilkS")
		)
		(fp_line
			(start 0.7874 0.4064)
			(end 0.7874 -0.4064)
			(stroke
				(width 0.1524)
				(type default)
			)
			(layer "B.SilkS")
		)
		(fp_line
			(start -0.7874 -0.4064)
			(end -0.7874 0.4064)
			(stroke
				(width 0.1524)
				(type default)
			)
			(layer "B.SilkS")
		)
		(fp_line
			(start 0.7874 -0.4064)
			(end -0.7874 -0.4064)
			(stroke
				(width 0.1524)
				(type default)
			)
			(layer "B.SilkS")
		)
		(fp_line
			(start -0.67945 0.3048)
			(end -0.120396 0.3048)
			(stroke
				(width 0.1)
				(type default)
			)
			(layer "B.Fab")
		)
		(fp_line
			(start -0.120396 0.3048)
			(end -0.120396 0.2794)
			(stroke
				(width 0.1)
				(type default)
			)
			(layer "B.Fab")
		)
		(fp_line
			(start 0.12065 0.3048)
			(end 0.67945 0.3048)
			(stroke
				(width 0.1)
				(type default)
			)
			(layer "B.Fab")
		)
		(fp_line
			(start 0.67945 0.3048)
			(end 0.67945 -0.305054)
			(stroke
				(width 0.1)
				(type default)
			)
			(layer "B.Fab")
		)
		(fp_line
			(start -0.120396 0.2794)
			(end 0.12065 0.2794)
			(stroke
				(width 0.1)
				(type default)
			)
			(layer "B.Fab")
		)
		(fp_line
			(start 0.12065 0.2794)
			(end 0.12065 0.3048)
			(stroke
				(width 0.1)
				(type default)
			)
			(layer "B.Fab")
		)
		(fp_line
			(start -0.12065 -0.2794)
			(end -0.12065 -0.3048)
			(stroke
				(width 0.1)
				(type default)
			)
			(layer "B.Fab")
		)
		(fp_line
			(start 0.12065 -0.2794)
			(end -0.12065 -0.2794)
			(stroke
				(width 0.1)
				(type default)
			)
			(layer "B.Fab")
		)
		(fp_line
			(start -0.67945 -0.3048)
			(end -0.67945 0.3048)
			(stroke
				(width 0.1)
				(type default)
			)
			(layer "B.Fab")
		)
		(fp_line
			(start -0.12065 -0.3048)
			(end -0.67945 -0.3048)
			(stroke
				(width 0.1)
				(type default)
			)
			(layer "B.Fab")
		)
		(fp_line
			(start 0.12065 -0.305054)
			(end 0.12065 -0.2794)
			(stroke
				(width 0.1)
				(type default)
			)
			(layer "B.Fab")
		)
		(fp_line
			(start 0.67945 -0.305054)
			(end 0.12065 -0.305054)
			(stroke
				(width 0.1)
				(type default)
			)
			(layer "B.Fab")
		)
		(pad "1" smd circle
			(at 0.40005 0 90)
			(size 0 0)
			(layers "B.Cu" "B.Mask" "B.Paste")
			(net "P1V2_P1V0_I3C_VDDL1")
		)
		(pad "2" smd circle
			(at -0.40005 0 90)
			(size 0 0)
			(layers "B.Cu" "B.Mask" "B.Paste")
			(net "I3C3_SPD_SCL")
		)
	)
)
